(kicad_pcb
	(version 20260206)
	(generator "pcbnew")
	(generator_version "10.0")
	(general
		(thickness 1.6)
		(legacy_teardrops no)
	)
	(paper "A4")
	(title_block
		(title "Wiwynn_Tioga_Pass_MB.brd")
		(comment 1 "Tioga Pass / footprints 1673-1680 of 4770")
	)
	(layers
		(0 "F.Cu" signal "TOP")
		(4 "In1.Cu" signal "L2GND")
		(6 "In2.Cu" signal "L3")
		(8 "In3.Cu" signal "L4GND")
		(10 "In4.Cu" signal "L5")
		(12 "In5.Cu" signal "L6GND")
		(14 "In6.Cu" signal "L7VCC")
		(16 "In7.Cu" signal "L8VCC")
		(18 "In8.Cu" signal "L9GND")
		(20 "In9.Cu" signal "L10")
		(22 "In10.Cu" signal "L11GND")
		(24 "In11.Cu" signal "L12")
		(26 "In12.Cu" signal "L13GND")
		(2 "B.Cu" signal "BOTTOM")
		(9 "F.Adhes" user "F.Adhesive")
		(11 "B.Adhes" user "B.Adhesive")
		(13 "F.Paste" user "Package Geometry/Pastemask Top")
		(15 "B.Paste" user "Package Geometry/Pastemask Bottom")
		(5 "F.SilkS" user "Ref Des/Silkscreen Top")
		(7 "B.SilkS" user "Ref Des/Silkscreen Bottom")
		(1 "F.Mask" user "Board Geometry/Soldermask Top")
		(3 "B.Mask" user "Board Geometry/Soldermask Bottom")
		(17 "Dwgs.User" user "User.Drawings")
		(19 "Cmts.User" user "User.Comments")
		(21 "Eco1.User" user "User.Eco1")
		(23 "Eco2.User" user "User.Eco2")
		(25 "Edge.Cuts" user "Board Geometry/Outline")
		(27 "Margin" user)
		(31 "F.CrtYd" user "Package Geometry/Place Bound Top")
		(29 "B.CrtYd" user "Package Geometry/Place Bound Bottom")
		(35 "F.Fab" user "Ref Des/Assembly Top")
		(33 "B.Fab" user "Ref Des/Assembly Bottom")
	)
	(footprint ""
		(layer "F.Cu")
		(at 349.6437 -27.9654 180)
		(property "Reference" "C7F6"
			(at 0 0 180)
			(layer "F.SilkS")
			(hide yes)
			(effects
				(font
					(size 1.27 1.27)
				)
			)
		)
		(property "Value" ""
			(at 0 0 180)
			(layer "F.Fab")
			(effects
				(font
					(size 1.27 1.27)
				)
			)
		)
		(duplicate_pad_numbers_are_jumpers no)
		(fp_rect
			(start -0.3048 -0.1016)
			(end 0.3048 0.9906)
			(stroke
				(width 0)
				(type default)
			)
			(fill no)
			(layer "F.CrtYd")
		)
		(fp_line
			(start 0.3048 0.9906)
			(end 0.3048 -0.1016)
			(stroke
				(width 0.1)
				(type default)
			)
			(layer "F.Fab")
		)
		(fp_line
			(start 0.3048 -0.1016)
			(end -0.3048 -0.1016)
			(stroke
				(width 0.1)
				(type default)
			)
			(layer "F.Fab")
		)
		(fp_line
			(start -0.3048 0.9906)
			(end 0.3048 0.9906)
			(stroke
				(width 0.1)
				(type default)
			)
			(layer "F.Fab")
		)
		(fp_line
			(start -0.3048 -0.1016)
			(end -0.3048 0.9906)
			(stroke
				(width 0.1)
				(type default)
			)
			(layer "F.Fab")
		)
		(pad "1" smd rect
			(at 0 0 180)
			(size 0.508 0.508)
			(layers "F.Cu" "F.Mask" "F.Paste")
			(net "VR_FET_SW_P12V_STBY_PVPP_ABC")
		)
		(pad "2" smd rect
			(at 0 0.889 180)
			(size 0.508 0.508)
			(layers "F.Cu" "F.Mask" "F.Paste")
			(net "GND")
		)
		(zone
			(layer "F.Cu")
			(hatch none 0.5)
			(connect_pads
				(clearance 0)
			)
			(min_thickness 0.25)
			(keepout
				(tracks not_allowed)
				(vias allowed)
				(pads allowed)
				(copperpour not_allowed)
				(footprints allowed)
			)
			(placement
				(enabled no)
				(sheetname "")
			)
			(fill
				(thermal_gap 0.5)
				(thermal_bridge_width 0.5)
				(island_removal_mode 0)
			)
			(polygon
				(pts
					(xy 349.8977 -28.2194) (xy 349.8977 -28.6004) (xy 349.3897 -28.6004) (xy 349.3897 -28.2194)
				)
			)
		)
		(zone
			(layer "F.Cu")
			(hatch none 0.5)
			(connect_pads
				(clearance 0)
			)
			(min_thickness 0.25)
			(keepout
				(tracks allowed)
				(vias not_allowed)
				(pads allowed)
				(copperpour not_allowed)
				(footprints allowed)
			)
			(placement
				(enabled no)
				(sheetname "")
			)
			(fill
				(thermal_gap 0.5)
				(thermal_bridge_width 0.5)
				(island_removal_mode 0)
			)
			(polygon
				(pts
					(xy 349.8977 -28.2194) (xy 349.8977 -28.6004) (xy 349.3897 -28.6004) (xy 349.3897 -28.2194)
				)
			)
		)
	)
	(footprint ""
		(layer "F.Cu")
		(at 23.46198 -84.14258)
		(property "Reference" "R1D12"
			(at 0 0 0)
			(layer "F.SilkS")
			(hide yes)
			(effects
				(font
					(size 1.27 1.27)
				)
			)
		)
		(property "Value" ""
			(at 0 0 0)
			(layer "F.Fab")
			(effects
				(font
					(size 1.27 1.27)
				)
			)
		)
		(duplicate_pad_numbers_are_jumpers no)
		(fp_poly
			(pts
				(xy -0.2794 -0.1016) (xy 0.2794 -0.1016) (xy 0.2794 0.9906) (xy -0.2794 0.9906)
			)
			(stroke
				(width 0)
				(type default)
			)
			(fill no)
			(layer "F.CrtYd")
		)
		(fp_line
			(start -0.2794 -0.1016)
			(end -0.2794 0.9906)
			(stroke
				(width 0.1)
				(type default)
			)
			(layer "F.Fab")
		)
		(fp_line
			(start -0.2794 0.9906)
			(end 0.2794 0.9906)
			(stroke
				(width 0.1)
				(type default)
			)
			(layer "F.Fab")
		)
		(fp_line
			(start 0.2794 -0.1016)
			(end -0.2794 -0.1016)
			(stroke
				(width 0.1)
				(type default)
			)
			(layer "F.Fab")
		)
		(fp_line
			(start 0.2794 0.9906)
			(end 0.2794 -0.1016)
			(stroke
				(width 0.1)
				(type default)
			)
			(layer "F.Fab")
		)
		(pad "1" smd rect
			(at 0 0)
			(size 0.508 0.508)
			(layers "F.Cu" "F.Mask" "F.Paste")
			(net "A_HSC_LOW")
		)
		(pad "2" smd rect
			(at 0 0.889)
			(size 0.508 0.508)
			(layers "F.Cu" "F.Mask" "F.Paste")
			(net "AGND_HSC")
		)
		(zone
			(layer "F.Cu")
			(hatch none 0.5)
			(connect_pads
				(clearance 0)
			)
			(min_thickness 0.25)
			(keepout
				(tracks allowed)
				(vias not_allowed)
				(pads allowed)
				(copperpour not_allowed)
				(footprints allowed)
			)
			(placement
				(enabled no)
				(sheetname "")
			)
			(fill
				(thermal_gap 0.5)
				(thermal_bridge_width 0.5)
				(island_removal_mode 0)
			)
			(polygon
				(pts
					(xy 23.20798 -83.88858) (xy 23.71598 -83.88858) (xy 23.71598 -83.50758) (xy 23.20798 -83.50758)
				)
			)
		)
		(zone
			(layer "F.Cu")
			(hatch none 0.5)
			(connect_pads
				(clearance 0)
			)
			(min_thickness 0.25)
			(keepout
				(tracks not_allowed)
				(vias allowed)
				(pads allowed)
				(copperpour not_allowed)
				(footprints allowed)
			)
			(placement
				(enabled no)
				(sheetname "")
			)
			(fill
				(thermal_gap 0.5)
				(thermal_bridge_width 0.5)
				(island_removal_mode 0)
			)
			(polygon
				(pts
					(xy 23.20798 -83.50758) (xy 23.71598 -83.50758) (xy 23.71598 -83.88858) (xy 23.20798 -83.88858)
				)
			)
		)
	)
	(footprint ""
		(layer "F.Cu")
		(at 9.017 10.7315 -90)
		(property "Reference" "T1P25"
			(at 0 0 270)
			(layer "F.SilkS")
			(hide yes)
			(effects
				(font
					(size 1.27 1.27)
				)
			)
		)
		(property "Value" "*"
			(at 0 -3.44805 270)
			(unlocked yes)
			(layer "F.Fab")
			(hide yes)
			(effects
				(font
					(size 0.889 0.889)
					(thickness 0.1524)
				)
			)
		)
		(property "Device Type" "TPAD-SE-2P-GP_DISCRET-GA1-TPADA"
			(at 0 -4.97205 270)
			(unlocked yes)
			(layer "F.Fab")
			(hide yes)
			(effects
				(font
					(size 0.889 0.889)
					(thickness 0.1524)
				)
			)
		)
		(duplicate_pad_numbers_are_jumpers no)
		(fp_line
			(start -1.016 2.286)
			(end -1.016 -2.286)
			(stroke
				(width 0.1524)
				(type default)
			)
			(layer "F.SilkS")
		)
		(fp_line
			(start 1.016 2.286)
			(end -1.016 2.286)
			(stroke
				(width 0.1524)
				(type default)
			)
			(layer "F.SilkS")
		)
		(fp_line
			(start -1.016 -2.286)
			(end 1.016 -2.286)
			(stroke
				(width 0.1524)
				(type default)
			)
			(layer "F.SilkS")
		)
		(fp_line
			(start 1.016 -2.286)
			(end 1.016 2.286)
			(stroke
				(width 0.1524)
				(type default)
			)
			(layer "F.SilkS")
		)
		(fp_rect
			(start -1.27 2.54)
			(end 1.27 -2.54)
			(stroke
				(width 0)
				(type default)
			)
			(fill no)
			(layer "F.CrtYd")
		)
		(fp_rect
			(start -1.27 2.54)
			(end 1.27 -2.54)
			(stroke
				(width 0)
				(type default)
			)
			(fill no)
			(layer "F.Fab")
		)
		(pad "1" thru_hole circle
			(at 0 -1.27 270)
			(size 1.524 1.524)
			(drill 0.9144)
			(layers "*.Cu" "*.Mask")
			(remove_unused_layers no)
			(net "L1_40OHM_6INCH")
			(clearance -0.0508)
			(thermal_gap 0.127)
			(padstack
				(mode front_inner_back)
				(layer "Inner"
					(shape circle)
					(size 1.1684 1.1684)
					(clearance 0.127)
				)
				(layer "B.Cu"
					(shape circle)
					(size 1.524 1.524)
					(clearance -0.0508)
				)
			)
		)
		(pad "GND1" thru_hole rect
			(at 0 1.27 270)
			(size 1.524 1.524)
			(drill 0.9144)
			(layers "*.Cu" "*.Mask")
			(remove_unused_layers no)
			(net "GND")
			(clearance -0.0508)
			(thermal_gap 0.127)
			(padstack
				(mode front_inner_back)
				(layer "Inner"
					(shape circle)
					(size 1.1684 1.1684)
					(clearance 0.127)
				)
				(layer "B.Cu"
					(shape rect)
					(size 1.524 1.524)
					(clearance -0.0508)
				)
			)
		)
	)
	(footprint ""
		(layer "F.Cu")
		(at 33.2105 -92.9386 90)
		(property "Reference" "C1C25"
			(at 0 0 90)
			(layer "F.SilkS")
			(hide yes)
			(effects
				(font
					(size 1.27 1.27)
				)
			)
		)
		(property "Value" ""
			(at 0 0 90)
			(layer "F.Fab")
			(effects
				(font
					(size 1.27 1.27)
				)
			)
		)
		(duplicate_pad_numbers_are_jumpers no)
		(fp_rect
			(start 0.3048 0.9906)
			(end -0.3048 -0.1016)
			(stroke
				(width 0)
				(type default)
			)
			(fill no)
			(layer "F.CrtYd")
		)
		(fp_line
			(start 0.3048 -0.1016)
			(end -0.3048 -0.1016)
			(stroke
				(width 0.1)
				(type default)
			)
			(layer "F.Fab")
		)
		(fp_line
			(start -0.3048 -0.1016)
			(end -0.3048 0.9906)
			(stroke
				(width 0.1)
				(type default)
			)
			(layer "F.Fab")
		)
		(fp_line
			(start 0.3048 0.9906)
			(end 0.3048 -0.1016)
			(stroke
				(width 0.1)
				(type default)
			)
			(layer "F.Fab")
		)
		(fp_line
			(start -0.3048 0.9906)
			(end 0.3048 0.9906)
			(stroke
				(width 0.1)
				(type default)
			)
			(layer "F.Fab")
		)
		(pad "1" smd rect
			(at 0 0 90)
			(size 0.508 0.508)
			(layers "F.Cu" "F.Mask" "F.Paste")
			(net "VR_FET_SW_P12V_STBY_PVCCIN_CPU1")
		)
		(pad "2" smd rect
			(at 0 0.889 90)
			(size 0.508 0.508)
			(layers "F.Cu" "F.Mask" "F.Paste")
			(net "GND")
		)
		(zone
			(layer "F.Cu")
			(hatch none 0.5)
			(connect_pads
				(clearance 0)
			)
			(min_thickness 0.25)
			(keepout
				(tracks allowed)
				(vias not_allowed)
				(pads allowed)
				(copperpour not_allowed)
				(footprints allowed)
			)
			(placement
				(enabled no)
				(sheetname "")
			)
			(fill
				(thermal_gap 0.5)
				(thermal_bridge_width 0.5)
				(island_removal_mode 0)
			)
			(polygon
				(pts
					(xy 33.8455 -93.1926) (xy 33.4645 -93.1926) (xy 33.4645 -92.6846) (xy 33.8455 -92.6846)
				)
			)
		)
		(zone
			(layer "F.Cu")
			(hatch none 0.5)
			(connect_pads
				(clearance 0)
			)
			(min_thickness 0.25)
			(keepout
				(tracks not_allowed)
				(vias allowed)
				(pads allowed)
				(copperpour not_allowed)
				(footprints allowed)
			)
			(placement
				(enabled no)
				(sheetname "")
			)
			(fill
				(thermal_gap 0.5)
				(thermal_bridge_width 0.5)
				(island_removal_mode 0)
			)
			(polygon
				(pts
					(xy 33.8455 -93.1926) (xy 33.4645 -93.1926) (xy 33.4645 -92.6846) (xy 33.8455 -92.6846)
				)
			)
		)
	)
	(footprint ""
		(layer "F.Cu")
		(at 267.146024 -68.412614 180)
		(property "Reference" "C5D57"
			(at 0 0 180)
			(layer "F.SilkS")
			(hide yes)
			(effects
				(font
					(size 1.27 1.27)
				)
			)
		)
		(property "Value" ""
			(at 0 0 180)
			(layer "F.Fab")
			(effects
				(font
					(size 1.27 1.27)
				)
			)
		)
		(duplicate_pad_numbers_are_jumpers no)
		(fp_poly
			(pts
				(xy -0.4953 -0.2032) (xy 0.4953 -0.2032) (xy 0.4953 1.6002) (xy -0.4953 1.6002)
			)
			(stroke
				(width 0)
				(type default)
			)
			(fill no)
			(layer "F.CrtYd")
		)
		(fp_line
			(start 0.4953 1.6002)
			(end -0.4953 1.6002)
			(stroke
				(width 0.1)
				(type default)
			)
			(layer "F.Fab")
		)
		(fp_line
			(start 0.4953 -0.2032)
			(end 0.4953 1.6002)
			(stroke
				(width 0.1)
				(type default)
			)
			(layer "F.Fab")
		)
		(fp_line
			(start -0.4953 1.6002)
			(end -0.4953 -0.2032)
			(stroke
				(width 0.1)
				(type default)
			)
			(layer "F.Fab")
		)
		(fp_line
			(start -0.4953 -0.2032)
			(end 0.4953 -0.2032)
			(stroke
				(width 0.1)
				(type default)
			)
			(layer "F.Fab")
		)
		(pad "1" smd rect
			(at 0 0 180)
			(size 0.762 0.889)
			(layers "F.Cu" "F.Mask" "F.Paste")
			(net "PVDDQ_ABC")
		)
		(pad "2" smd rect
			(at 0 1.397 180)
			(size 0.762 0.889)
			(layers "F.Cu" "F.Mask" "F.Paste")
			(net "GND")
		)
		(zone
			(layer "F.Cu")
			(hatch none 0.5)
			(connect_pads
				(clearance 0)
			)
			(min_thickness 0.25)
			(keepout
				(tracks not_allowed)
				(vias allowed)
				(pads allowed)
				(copperpour not_allowed)
				(footprints allowed)
			)
			(placement
				(enabled no)
				(sheetname "")
			)
			(fill
				(thermal_gap 0.5)
				(thermal_bridge_width 0.5)
				(island_removal_mode 0)
			)
			(polygon
				(pts
					(xy 267.527024 -68.857114) (xy 266.765024 -68.857114) (xy 266.765024 -69.365114) (xy 267.527024 -69.365114)
				)
			)
		)
	)
	(footprint ""
		(layer "F.Cu")
		(at 190.1698 -69.3039 180)
		(property "Reference" "RF4"
			(at -0.8382 -0.67818 180)
			(unlocked yes)
			(layer "F.SilkS")
			(effects
				(font
					(size 0.4064 0.254)
					(thickness 0.1524)
				)
				(justify left)
			)
		)
		(property "Value" ""
			(at 0 0 180)
			(layer "F.Fab")
			(effects
				(font
					(size 1.27 1.27)
				)
			)
		)
		(duplicate_pad_numbers_are_jumpers no)
		(fp_poly
			(pts
				(xy -0.2794 -0.1016) (xy 0.2794 -0.1016) (xy 0.2794 0.9906) (xy -0.2794 0.9906)
			)
			(stroke
				(width 0)
				(type default)
			)
			(fill no)
			(layer "F.CrtYd")
		)
		(fp_line
			(start 0.2794 0.9906)
			(end 0.2794 -0.1016)
			(stroke
				(width 0.1)
				(type default)
			)
			(layer "F.Fab")
		)
		(fp_line
			(start 0.2794 -0.1016)
			(end -0.2794 -0.1016)
			(stroke
				(width 0.1)
				(type default)
			)
			(layer "F.Fab")
		)
		(fp_line
			(start -0.2794 0.9906)
			(end 0.2794 0.9906)
			(stroke
				(width 0.1)
				(type default)
			)
			(layer "F.Fab")
		)
		(fp_line
			(start -0.2794 -0.1016)
			(end -0.2794 0.9906)
			(stroke
				(width 0.1)
				(type default)
			)
			(layer "F.Fab")
		)
		(pad "1" smd rect
			(at 0 0 180)
			(size 0.508 0.508)
			(layers "F.Cu" "F.Mask" "F.Paste")
			(net "VR_PVCCIN_CPU0_AIREF4")
		)
		(pad "2" smd rect
			(at 0 0.889 180)
			(size 0.508 0.508)
			(layers "F.Cu" "F.Mask" "F.Paste")
			(net "ISENSE_PVCCIN_CPU0_PH4_IMON")
		)
		(zone
			(layer "F.Cu")
			(hatch none 0.5)
			(connect_pads
				(clearance 0)
			)
			(min_thickness 0.25)
			(keepout
				(tracks not_allowed)
				(vias allowed)
				(pads allowed)
				(copperpour not_allowed)
				(footprints allowed)
			)
			(placement
				(enabled no)
				(sheetname "")
			)
			(fill
				(thermal_gap 0.5)
				(thermal_bridge_width 0.5)
				(island_removal_mode 0)
			)
			(polygon
				(pts
					(xy 190.4238 -69.9389) (xy 189.9158 -69.9389) (xy 189.9158 -69.5579) (xy 190.4238 -69.5579)
				)
			)
		)
		(zone
			(layer "F.Cu")
			(hatch none 0.5)
			(connect_pads
				(clearance 0)
			)
			(min_thickness 0.25)
			(keepout
				(tracks allowed)
				(vias not_allowed)
				(pads allowed)
				(copperpour not_allowed)
				(footprints allowed)
			)
			(placement
				(enabled no)
				(sheetname "")
			)
			(fill
				(thermal_gap 0.5)
				(thermal_bridge_width 0.5)
				(island_removal_mode 0)
			)
			(polygon
				(pts
					(xy 190.4238 -69.5579) (xy 189.9158 -69.5579) (xy 189.9158 -69.9389) (xy 190.4238 -69.9389)
				)
			)
		)
	)
	(footprint ""
		(layer "F.Cu")
		(at 403.606 3.2004 90)
		(property "Reference" "R8G13"
			(at 0 0 90)
			(layer "F.SilkS")
			(hide yes)
			(effects
				(font
					(size 1.27 1.27)
				)
			)
		)
		(property "Value" ""
			(at 0 0 90)
			(layer "F.Fab")
			(effects
				(font
					(size 1.27 1.27)
				)
			)
		)
		(duplicate_pad_numbers_are_jumpers no)
		(fp_poly
			(pts
				(xy -0.2794 -0.1016) (xy 0.2794 -0.1016) (xy 0.2794 0.9906) (xy -0.2794 0.9906)
			)
			(stroke
				(width 0)
				(type default)
			)
			(fill no)
			(layer "F.CrtYd")
		)
		(fp_line
			(start 0.2794 -0.1016)
			(end -0.2794 -0.1016)
			(stroke
				(width 0.1)
				(type default)
			)
			(layer "F.Fab")
		)
		(fp_line
			(start -0.2794 -0.1016)
			(end -0.2794 0.9906)
			(stroke
				(width 0.1)
				(type default)
			)
			(layer "F.Fab")
		)
		(fp_line
			(start 0.2794 0.9906)
			(end 0.2794 -0.1016)
			(stroke
				(width 0.1)
				(type default)
			)
			(layer "F.Fab")
		)
		(fp_line
			(start -0.2794 0.9906)
			(end 0.2794 0.9906)
			(stroke
				(width 0.1)
				(type default)
			)
			(layer "F.Fab")
		)
		(pad "1" smd rect
			(at 0 0 90)
			(size 0.508 0.508)
			(layers "F.Cu" "F.Mask" "F.Paste")
			(net "JTAG_PLD_TMS")
		)
		(pad "2" smd rect
			(at 0 0.889 90)
			(size 0.508 0.508)
			(layers "F.Cu" "F.Mask" "F.Paste")
			(net "JTAG_PLD_TMS_MUX")
		)
		(zone
			(layer "F.Cu")
			(hatch none 0.5)
			(connect_pads
				(clearance 0)
			)
			(min_thickness 0.25)
			(keepout
				(tracks allowed)
				(vias not_allowed)
				(pads allowed)
				(copperpour not_allowed)
				(footprints allowed)
			)
			(placement
				(enabled no)
				(sheetname "")
			)
			(fill
				(thermal_gap 0.5)
				(thermal_bridge_width 0.5)
				(island_removal_mode 0)
			)
			(polygon
				(pts
					(xy 403.86 3.4544) (xy 403.86 2.9464) (xy 404.241 2.9464) (xy 404.241 3.4544)
				)
			)
		)
		(zone
			(layer "F.Cu")
			(hatch none 0.5)
			(connect_pads
				(clearance 0)
			)
			(min_thickness 0.25)
			(keepout
				(tracks not_allowed)
				(vias allowed)
				(pads allowed)
				(copperpour not_allowed)
				(footprints allowed)
			)
			(placement
				(enabled no)
				(sheetname "")
			)
			(fill
				(thermal_gap 0.5)
				(thermal_bridge_width 0.5)
				(island_removal_mode 0)
			)
			(polygon
				(pts
					(xy 404.241 3.4544) (xy 404.241 2.9464) (xy 403.86 2.9464) (xy 403.86 3.4544)
				)
			)
		)
	)
	(footprint ""
		(layer "F.Cu")
		(at 405.384 -46.8249 180)
		(property "Reference" "R2T63"
			(at 0 0 180)
			(layer "F.SilkS")
			(hide yes)
			(effects
				(font
					(size 1.27 1.27)
				)
			)
		)
		(property "Value" ""
			(at 0 0 180)
			(layer "F.Fab")
			(effects
				(font
					(size 1.27 1.27)
				)
			)
		)
		(duplicate_pad_numbers_are_jumpers no)
		(fp_poly
			(pts
				(xy -0.2794 -0.1016) (xy 0.2794 -0.1016) (xy 0.2794 0.9906) (xy -0.2794 0.9906)
			)
			(stroke
				(width 0)
				(type default)
			)
			(fill no)
			(layer "F.CrtYd")
		)
		(fp_line
			(start 0.2794 0.9906)
			(end 0.2794 -0.1016)
			(stroke
				(width 0.1)
				(type default)
			)
			(layer "F.Fab")
		)
		(fp_line
			(start 0.2794 -0.1016)
			(end -0.2794 -0.1016)
			(stroke
				(width 0.1)
				(type default)
			)
			(layer "F.Fab")
		)
		(fp_line
			(start -0.2794 0.9906)
			(end 0.2794 0.9906)
			(stroke
				(width 0.1)
				(type default)
			)
			(layer "F.Fab")
		)
		(fp_line
			(start -0.2794 -0.1016)
			(end -0.2794 0.9906)
			(stroke
				(width 0.1)
				(type default)
			)
			(layer "F.Fab")
		)
		(pad "1" smd rect
			(at 0 0 180)
			(size 0.508 0.508)
			(layers "F.Cu" "F.Mask" "F.Paste")
			(net "FM_CPU_ERR1_LVT3_N")
		)
		(pad "2" smd rect
			(at 0 0.889 180)
			(size 0.508 0.508)
			(layers "F.Cu" "F.Mask" "F.Paste")
			(net "FM_CPU_ERR1_PCH_N")
		)
		(zone
			(layer "F.Cu")
			(hatch none 0.5)
			(connect_pads
				(clearance 0)
			)
			(min_thickness 0.25)
			(keepout
				(tracks not_allowed)
				(vias allowed)
				(pads allowed)
				(copperpour not_allowed)
				(footprints allowed)
			)
			(placement
				(enabled no)
				(sheetname "")
			)
			(fill
				(thermal_gap 0.5)
				(thermal_bridge_width 0.5)
				(island_removal_mode 0)
			)
			(polygon
				(pts
					(xy 405.638 -47.4599) (xy 405.13 -47.4599) (xy 405.13 -47.0789) (xy 405.638 -47.0789)
				)
			)
		)
		(zone
			(layer "F.Cu")
			(hatch none 0.5)
			(connect_pads
				(clearance 0)
			)
			(min_thickness 0.25)
			(keepout
				(tracks allowed)
				(vias not_allowed)
				(pads allowed)
				(copperpour not_allowed)
				(footprints allowed)
			)
			(placement
				(enabled no)
				(sheetname "")
			)
			(fill
				(thermal_gap 0.5)
				(thermal_bridge_width 0.5)
				(island_removal_mode 0)
			)
			(polygon
				(pts
					(xy 405.638 -47.0789) (xy 405.13 -47.0789) (xy 405.13 -47.4599) (xy 405.638 -47.4599)
				)
			)
		)
	)
)
